(kicad_pcb
	(version 20260206)
	(generator "pcbnew")
	(generator_version "10.0")
	(general
		(thickness 1.6)
		(legacy_teardrops no)
	)
	(paper "A4")
	(title_block
		(title "baseboard — 13948-1b.1110WZS1818.brd")
		(comment 1 "Honey Badger (Wiwynn) / footprints 1071-1077 of 2523")
	)
	(layers
		(0 "F.Cu" signal "TOP")
		(4 "In1.Cu" signal "L2GND")
		(6 "In2.Cu" signal "L3")
		(8 "In3.Cu" signal "L4VCC")
		(10 "In4.Cu" signal "L5VCC")
		(12 "In5.Cu" signal "L6")
		(14 "In6.Cu" signal "L7GND")
		(2 "B.Cu" signal "BOTTOM")
		(9 "F.Adhes" user "F.Adhesive")
		(11 "B.Adhes" user "B.Adhesive")
		(13 "F.Paste" user "Package Geometry/Pastemask Top")
		(15 "B.Paste" user "Package Geometry/Pastemask Bottom")
		(5 "F.SilkS" user "Ref Des/Silkscreen Top")
		(7 "B.SilkS" user "Ref Des/Silkscreen Bottom")
		(1 "F.Mask" user "Board Geometry/Soldermask Top")
		(3 "B.Mask" user "Board Geometry/Soldermask Bottom")
		(17 "Dwgs.User" user "User.Drawings")
		(19 "Cmts.User" user "User.Comments")
		(21 "Eco1.User" user "User.Eco1")
		(23 "Eco2.User" user "User.Eco2")
		(25 "Edge.Cuts" user "Board Geometry/Outline")
		(27 "Margin" user)
		(31 "F.CrtYd" user "Package Geometry/Place Bound Top")
		(29 "B.CrtYd" user "Package Geometry/Place Bound Bottom")
		(35 "F.Fab" user "Ref Des/Assembly Top")
		(33 "B.Fab" user "Ref Des/Assembly Bottom")
	)
	(footprint ""
		(layer "F.Cu")
		(at 40.52697 -137.16 180)
		(property "Reference" "Q15"
			(at 0 0 180)
			(layer "F.SilkS")
			(hide yes)
			(effects
				(font
					(size 1.27 1.27)
				)
			)
		)
		(property "Value" "2N7002A-7-GP"
			(at 0.127 -8.9662 180)
			(unlocked yes)
			(layer "F.Fab")
			(hide yes)
			(effects
				(font
					(size 1.016 1.016)
					(thickness 0.1524)
				)
			)
		)
		(property "Device Type" "SOT23DGS2D4H48"
			(at 0.127 -10.4902 180)
			(unlocked yes)
			(layer "F.Fab")
			(hide yes)
			(effects
				(font
					(size 1.016 1.016)
					(thickness 0.1524)
				)
			)
		)
		(duplicate_pad_numbers_are_jumpers no)
		(fp_line
			(start 1.651 1.778)
			(end 1.651 -1.778)
			(stroke
				(width 0.1524)
				(type default)
			)
			(layer "F.SilkS")
		)
		(fp_line
			(start 1.651 -1.778)
			(end -1.651 -1.778)
			(stroke
				(width 0.1524)
				(type default)
			)
			(layer "F.SilkS")
		)
		(fp_line
			(start -1.651 1.778)
			(end 1.651 1.778)
			(stroke
				(width 0.1524)
				(type default)
			)
			(layer "F.SilkS")
		)
		(fp_line
			(start -1.651 -1.778)
			(end -1.651 1.778)
			(stroke
				(width 0.1524)
				(type default)
			)
			(layer "F.SilkS")
		)
		(fp_poly
			(pts
				(xy -1.778 1.8796) (xy -1.778 -1.8796) (xy 1.778 -1.8796) (xy 1.778 1.8796)
			)
			(stroke
				(width 0)
				(type default)
			)
			(fill no)
			(layer "F.CrtYd")
		)
		(fp_poly
			(pts
				(xy -1.778 1.8796) (xy -1.778 -1.8796) (xy 1.778 -1.8796) (xy 1.778 1.8796)
			)
			(stroke
				(width 0)
				(type default)
			)
			(fill no)
			(layer "F.Fab")
		)
		(pad "D" smd custom
			(at 0 -0.9525 180)
			(size 0.1905 0.1905)
			(layers "F.Cu" "F.Mask" "F.Paste")
			(net "P3V3_STBY_R5")
			(options
				(clearance outline)
				(anchor circle)
			)
			(primitives
				(gr_poly
					(pts
						(arc
							(start -0.1778 0.5715)
							(mid -0.321484 0.511984)
							(end -0.381 0.3683)
						)
						(arc
							(start -0.381 -0.3683)
							(mid -0.321484 -0.511984)
							(end -0.1778 -0.5715)
						)
						(arc
							(start 0.1778 -0.5715)
							(mid 0.321484 -0.511984)
							(end 0.381 -0.3683)
						)
						(arc
							(start 0.381 0.3683)
							(mid 0.321484 0.511984)
							(end 0.1778 0.5715)
						)
					)
					(width 0)
					(fill yes)
				)
			)
		)
		(pad "G" smd custom
			(at -0.98425 0.9525 180)
			(size 0.1905 0.1905)
			(layers "F.Cu" "F.Mask" "F.Paste")
			(net "BMC_RST_EXPANDER")
			(options
				(clearance outline)
				(anchor circle)
			)
			(primitives
				(gr_poly
					(pts
						(arc
							(start -0.1778 0.5715)
							(mid -0.321484 0.511984)
							(end -0.381 0.3683)
						)
						(arc
							(start -0.381 -0.3683)
							(mid -0.321484 -0.511984)
							(end -0.1778 -0.5715)
						)
						(arc
							(start 0.1778 -0.5715)
							(mid 0.321484 -0.511984)
							(end 0.381 -0.3683)
						)
						(arc
							(start 0.381 0.3683)
							(mid 0.321484 0.511984)
							(end 0.1778 0.5715)
						)
					)
					(width 0)
					(fill yes)
				)
			)
		)
		(pad "S" smd custom
			(at 0.98425 0.9525 180)
			(size 0.1905 0.1905)
			(layers "F.Cu" "F.Mask" "F.Paste")
			(net "GND")
			(options
				(clearance outline)
				(anchor circle)
			)
			(primitives
				(gr_poly
					(pts
						(arc
							(start -0.1778 0.5715)
							(mid -0.321484 0.511984)
							(end -0.381 0.3683)
						)
						(arc
							(start -0.381 -0.3683)
							(mid -0.321484 -0.511984)
							(end -0.1778 -0.5715)
						)
						(arc
							(start 0.1778 -0.5715)
							(mid 0.321484 -0.511984)
							(end 0.381 -0.3683)
						)
						(arc
							(start 0.381 0.3683)
							(mid 0.321484 0.511984)
							(end 0.1778 0.5715)
						)
					)
					(width 0)
					(fill yes)
				)
			)
		)
	)
	(footprint ""
		(layer "F.Cu")
		(at 111.322612 -205.867 180)
		(property "Reference" "SR883"
			(at 0 0 180)
			(layer "F.SilkS")
			(hide yes)
			(effects
				(font
					(size 1.27 1.27)
				)
			)
		)
		(property "Value" "0R2J-2-GP"
			(at 0.064008 -3.993896 180)
			(unlocked yes)
			(layer "F.Fab")
			(hide yes)
			(effects
				(font
					(size 1.016 1.016)
					(thickness 0.1524)
				)
			)
		)
		(property "Device Type" "R402H16"
			(at 0.064008 -5.517896 180)
			(unlocked yes)
			(layer "F.Fab")
			(hide yes)
			(effects
				(font
					(size 1.016 1.016)
					(thickness 0.1524)
				)
			)
		)
		(duplicate_pad_numbers_are_jumpers no)
		(fp_line
			(start 0.508 -0.9398)
			(end -0.508 -0.9398)
			(stroke
				(width 0.1524)
				(type default)
			)
			(layer "F.SilkS")
		)
		(fp_line
			(start -0.508 -0.9398)
			(end -0.508 0.9398)
			(stroke
				(width 0.1524)
				(type default)
			)
			(layer "F.SilkS")
		)
		(fp_rect
			(start -0.508 0.9398)
			(end 0.508 -0.9398)
			(stroke
				(width 0)
				(type default)
			)
			(fill no)
			(layer "F.CrtYd")
		)
		(fp_rect
			(start -0.508 0.9398)
			(end 0.508 -0.9398)
			(stroke
				(width 0)
				(type default)
			)
			(fill no)
			(layer "F.Fab")
		)
		(pad "1" smd custom
			(at 0 -0.4445 180)
			(size 0.1397 0.1397)
			(layers "F.Cu" "F.Mask" "F.Paste")
			(net "SAS_HDD_REDV_TX8_N")
			(options
				(clearance outline)
				(anchor circle)
			)
			(primitives
				(gr_poly
					(pts
						(arc
							(start -0.1778 -0.2794)
							(mid -0.249642 -0.249642)
							(end -0.2794 -0.1778)
						)
						(arc
							(start -0.2794 0.1778)
							(mid -0.249642 0.249642)
							(end -0.1778 0.2794)
						)
						(arc
							(start 0.1778 0.2794)
							(mid 0.249642 0.249642)
							(end 0.2794 0.1778)
						)
						(arc
							(start 0.2794 -0.1778)
							(mid 0.249642 -0.249642)
							(end 0.1778 -0.2794)
						)
					)
					(width 0)
					(fill yes)
				)
			)
		)
		(pad "2" smd custom
			(at 0 0.4445 180)
			(size 0.1397 0.1397)
			(layers "F.Cu" "F.Mask" "F.Paste")
			(net "REDV_TX8_N")
			(options
				(clearance outline)
				(anchor circle)
			)
			(primitives
				(gr_poly
					(pts
						(arc
							(start -0.1778 -0.2794)
							(mid -0.249642 -0.249642)
							(end -0.2794 -0.1778)
						)
						(arc
							(start -0.2794 0.1778)
							(mid -0.249642 0.249642)
							(end -0.1778 0.2794)
						)
						(arc
							(start 0.1778 0.2794)
							(mid 0.249642 0.249642)
							(end 0.2794 0.1778)
						)
						(arc
							(start 0.2794 -0.1778)
							(mid 0.249642 -0.249642)
							(end 0.1778 -0.2794)
						)
					)
					(width 0)
					(fill yes)
				)
			)
		)
	)
	(footprint ""
		(layer "F.Cu")
		(at 270.764 -188.341 -90)
		(property "Reference" "R174"
			(at 0 0 270)
			(layer "F.SilkS")
			(hide yes)
			(effects
				(font
					(size 1.27 1.27)
				)
			)
		)
		(property "Value" "4K7R2F-GP"
			(at 0.064008 -3.993896 270)
			(unlocked yes)
			(layer "F.Fab")
			(hide yes)
			(effects
				(font
					(size 1.016 1.016)
					(thickness 0.1524)
				)
			)
		)
		(property "Device Type" "R402H16"
			(at 0.064008 -5.517896 270)
			(unlocked yes)
			(layer "F.Fab")
			(hide yes)
			(effects
				(font
					(size 1.016 1.016)
					(thickness 0.1524)
				)
			)
		)
		(duplicate_pad_numbers_are_jumpers no)
		(fp_line
			(start -0.508 -0.9398)
			(end -0.508 0.9398)
			(stroke
				(width 0.1524)
				(type default)
			)
			(layer "F.SilkS")
		)
		(fp_line
			(start 0.508 -0.9398)
			(end -0.508 -0.9398)
			(stroke
				(width 0.1524)
				(type default)
			)
			(layer "F.SilkS")
		)
		(fp_rect
			(start -0.508 0.9398)
			(end 0.508 -0.9398)
			(stroke
				(width 0)
				(type default)
			)
			(fill no)
			(layer "F.CrtYd")
		)
		(fp_rect
			(start -0.508 0.9398)
			(end 0.508 -0.9398)
			(stroke
				(width 0)
				(type default)
			)
			(fill no)
			(layer "F.Fab")
		)
		(pad "1" smd custom
			(at 0 -0.4445 270)
			(size 0.1397 0.1397)
			(layers "F.Cu" "F.Mask" "F.Paste")
			(net "P3V3_STBY")
			(options
				(clearance outline)
				(anchor circle)
			)
			(primitives
				(gr_poly
					(pts
						(arc
							(start -0.1778 -0.2794)
							(mid -0.249642 -0.249642)
							(end -0.2794 -0.1778)
						)
						(arc
							(start -0.2794 0.1778)
							(mid -0.249642 0.249642)
							(end -0.1778 0.2794)
						)
						(arc
							(start 0.1778 0.2794)
							(mid 0.249642 0.249642)
							(end 0.2794 0.1778)
						)
						(arc
							(start 0.2794 -0.1778)
							(mid 0.249642 -0.249642)
							(end 0.1778 -0.2794)
						)
					)
					(width 0)
					(fill yes)
				)
			)
		)
		(pad "2" smd custom
			(at 0 0.4445 270)
			(size 0.1397 0.1397)
			(layers "F.Cu" "F.Mask" "F.Paste")
			(net "DP_RST_N")
			(options
				(clearance outline)
				(anchor circle)
			)
			(primitives
				(gr_poly
					(pts
						(arc
							(start -0.1778 -0.2794)
							(mid -0.249642 -0.249642)
							(end -0.2794 -0.1778)
						)
						(arc
							(start -0.2794 0.1778)
							(mid -0.249642 0.249642)
							(end -0.1778 0.2794)
						)
						(arc
							(start 0.1778 0.2794)
							(mid 0.249642 0.249642)
							(end 0.2794 0.1778)
						)
						(arc
							(start 0.2794 -0.1778)
							(mid 0.249642 -0.249642)
							(end 0.1778 -0.2794)
						)
					)
					(width 0)
					(fill yes)
				)
			)
		)
	)
	(footprint ""
		(layer "F.Cu")
		(at 95.89897 -87.376 90)
		(property "Reference" "SR775"
			(at 0 0 90)
			(layer "F.SilkS")
			(hide yes)
			(effects
				(font
					(size 1.27 1.27)
				)
			)
		)
		(property "Value" "4K75R2F-1-GP"
			(at 0.064008 -3.993896 90)
			(unlocked yes)
			(layer "F.Fab")
			(hide yes)
			(effects
				(font
					(size 1.016 1.016)
					(thickness 0.1524)
				)
			)
		)
		(property "Device Type" "R402H16"
			(at 0.064008 -5.517896 90)
			(unlocked yes)
			(layer "F.Fab")
			(hide yes)
			(effects
				(font
					(size 1.016 1.016)
					(thickness 0.1524)
				)
			)
		)
		(duplicate_pad_numbers_are_jumpers no)
		(fp_line
			(start 0.508 -0.9398)
			(end -0.508 -0.9398)
			(stroke
				(width 0.1524)
				(type default)
			)
			(layer "F.SilkS")
		)
		(fp_line
			(start -0.508 -0.9398)
			(end -0.508 0.9398)
			(stroke
				(width 0.1524)
				(type default)
			)
			(layer "F.SilkS")
		)
		(fp_rect
			(start -0.508 0.9398)
			(end 0.508 -0.9398)
			(stroke
				(width 0)
				(type default)
			)
			(fill no)
			(layer "F.CrtYd")
		)
		(fp_rect
			(start -0.508 0.9398)
			(end 0.508 -0.9398)
			(stroke
				(width 0)
				(type default)
			)
			(fill no)
			(layer "F.Fab")
		)
		(pad "1" smd custom
			(at 0 -0.4445 90)
			(size 0.1397 0.1397)
			(layers "F.Cu" "F.Mask" "F.Paste")
			(net "P1V8_E")
			(options
				(clearance outline)
				(anchor circle)
			)
			(primitives
				(gr_poly
					(pts
						(arc
							(start -0.1778 -0.2794)
							(mid -0.249642 -0.249642)
							(end -0.2794 -0.1778)
						)
						(arc
							(start -0.2794 0.1778)
							(mid -0.249642 0.249642)
							(end -0.1778 0.2794)
						)
						(arc
							(start 0.1778 0.2794)
							(mid 0.249642 0.249642)
							(end 0.2794 0.1778)
						)
						(arc
							(start 0.2794 -0.1778)
							(mid 0.249642 -0.249642)
							(end 0.1778 -0.2794)
						)
					)
					(width 0)
					(fill yes)
				)
			)
		)
		(pad "2" smd custom
			(at 0 0.4445 90)
			(size 0.1397 0.1397)
			(layers "F.Cu" "F.Mask" "F.Paste")
			(net "EXP_XM_WE_N")
			(options
				(clearance outline)
				(anchor circle)
			)
			(primitives
				(gr_poly
					(pts
						(arc
							(start -0.1778 -0.2794)
							(mid -0.249642 -0.249642)
							(end -0.2794 -0.1778)
						)
						(arc
							(start -0.2794 0.1778)
							(mid -0.249642 0.249642)
							(end -0.1778 0.2794)
						)
						(arc
							(start 0.1778 0.2794)
							(mid 0.249642 0.249642)
							(end 0.2794 0.1778)
						)
						(arc
							(start 0.2794 -0.1778)
							(mid 0.249642 -0.249642)
							(end 0.1778 -0.2794)
						)
					)
					(width 0)
					(fill yes)
				)
			)
		)
	)
	(footprint ""
		(layer "F.Cu")
		(at 333.701136 -197.366128 180)
		(property "Reference" "R194"
			(at 0 0 180)
			(layer "F.SilkS")
			(hide yes)
			(effects
				(font
					(size 1.27 1.27)
				)
			)
		)
		(property "Value" "8K2R2J-3-GP"
			(at 0.064008 -3.993896 180)
			(unlocked yes)
			(layer "F.Fab")
			(hide yes)
			(effects
				(font
					(size 1.016 1.016)
					(thickness 0.1524)
				)
			)
		)
		(property "Device Type" "R402H16"
			(at 0.064008 -5.517896 180)
			(unlocked yes)
			(layer "F.Fab")
			(hide yes)
			(effects
				(font
					(size 1.016 1.016)
					(thickness 0.1524)
				)
			)
		)
		(duplicate_pad_numbers_are_jumpers no)
		(fp_line
			(start 0.508 -0.9398)
			(end -0.508 -0.9398)
			(stroke
				(width 0.1524)
				(type default)
			)
			(layer "F.SilkS")
		)
		(fp_line
			(start -0.508 -0.9398)
			(end -0.508 0.9398)
			(stroke
				(width 0.1524)
				(type default)
			)
			(layer "F.SilkS")
		)
		(fp_rect
			(start -0.508 0.9398)
			(end 0.508 -0.9398)
			(stroke
				(width 0)
				(type default)
			)
			(fill no)
			(layer "F.CrtYd")
		)
		(fp_rect
			(start -0.508 0.9398)
			(end 0.508 -0.9398)
			(stroke
				(width 0)
				(type default)
			)
			(fill no)
			(layer "F.Fab")
		)
		(pad "1" smd custom
			(at 0 -0.4445 180)
			(size 0.1397 0.1397)
			(layers "F.Cu" "F.Mask" "F.Paste")
			(net "P3V3_STBY")
			(options
				(clearance outline)
				(anchor circle)
			)
			(primitives
				(gr_poly
					(pts
						(arc
							(start -0.1778 -0.2794)
							(mid -0.249642 -0.249642)
							(end -0.2794 -0.1778)
						)
						(arc
							(start -0.2794 0.1778)
							(mid -0.249642 0.249642)
							(end -0.1778 0.2794)
						)
						(arc
							(start 0.1778 0.2794)
							(mid 0.249642 0.249642)
							(end 0.2794 0.1778)
						)
						(arc
							(start 0.2794 -0.1778)
							(mid 0.249642 -0.249642)
							(end 0.1778 -0.2794)
						)
					)
					(width 0)
					(fill yes)
				)
			)
		)
		(pad "2" smd custom
			(at 0 0.4445 180)
			(size 0.1397 0.1397)
			(layers "F.Cu" "F.Mask" "F.Paste")
			(net "EEPROM_A2_R")
			(options
				(clearance outline)
				(anchor circle)
			)
			(primitives
				(gr_poly
					(pts
						(arc
							(start -0.1778 -0.2794)
							(mid -0.249642 -0.249642)
							(end -0.2794 -0.1778)
						)
						(arc
							(start -0.2794 0.1778)
							(mid -0.249642 0.249642)
							(end -0.1778 0.2794)
						)
						(arc
							(start 0.1778 0.2794)
							(mid 0.249642 0.249642)
							(end 0.2794 0.1778)
						)
						(arc
							(start 0.2794 -0.1778)
							(mid 0.249642 -0.249642)
							(end 0.1778 -0.2794)
						)
					)
					(width 0)
					(fill yes)
				)
			)
		)
	)
	(footprint ""
		(layer "F.Cu")
		(at 132.212842 -82.494882 90)
		(property "Reference" "SC1093"
			(at 0 0 90)
			(layer "F.SilkS")
			(hide yes)
			(effects
				(font
					(size 1.27 1.27)
				)
			)
		)
		(property "Value" "SCD01U10V1KX-GP"
			(at -2.8321 -1.7399 90)
			(unlocked yes)
			(layer "F.Fab")
			(hide yes)
			(effects
				(font
					(size 1.016 1.016)
					(thickness 0.1524)
				)
			)
		)
		(property "Device Type" "C0201H13"
			(at -2.8321 -3.2639 90)
			(unlocked yes)
			(layer "F.Fab")
			(hide yes)
			(effects
				(font
					(size 1.016 1.016)
					(thickness 0.1524)
				)
			)
		)
		(duplicate_pad_numbers_are_jumpers no)
		(fp_rect
			(start -0.2794 0.6477)
			(end 0.2794 -0.6477)
			(stroke
				(width 0)
				(type default)
			)
			(fill no)
			(layer "F.CrtYd")
		)
		(fp_rect
			(start -0.2794 0.6477)
			(end 0.2794 -0.6477)
			(stroke
				(width 0)
				(type default)
			)
			(fill no)
			(layer "F.Fab")
		)
		(pad "1" smd custom
			(at 0 -0.2794 90)
			(size 0.0762 0.0762)
			(layers "F.Cu" "F.Mask" "F.Paste")
			(net "SAS_HDD_TX13_N")
			(options
				(clearance outline)
				(anchor circle)
			)
			(primitives
				(gr_poly
					(pts
						(arc
							(start 0.1524 -0.127)
							(mid 0.137521 -0.162921)
							(end 0.1016 -0.1778)
						)
						(arc
							(start -0.1016 -0.1778)
							(mid -0.137521 -0.162921)
							(end -0.1524 -0.127)
						)
						(arc
							(start -0.1524 0.127)
							(mid -0.137521 0.162921)
							(end -0.1016 0.1778)
						)
						(arc
							(start 0.1016 0.1778)
							(mid 0.137521 0.162921)
							(end 0.1524 0.127)
						)
					)
					(width 0)
					(fill yes)
				)
			)
		)
		(pad "2" smd custom
			(at 0 0.2794 90)
			(size 0.0762 0.0762)
			(layers "F.Cu" "F.Mask" "F.Paste")
			(net "3008_SAS_RX_N1")
			(options
				(clearance outline)
				(anchor circle)
			)
			(primitives
				(gr_poly
					(pts
						(arc
							(start 0.1524 -0.127)
							(mid 0.137521 -0.162921)
							(end 0.1016 -0.1778)
						)
						(arc
							(start -0.1016 -0.1778)
							(mid -0.137521 -0.162921)
							(end -0.1524 -0.127)
						)
						(arc
							(start -0.1524 0.127)
							(mid -0.137521 0.162921)
							(end -0.1016 0.1778)
						)
						(arc
							(start 0.1016 0.1778)
							(mid 0.137521 0.162921)
							(end 0.1524 0.127)
						)
					)
					(width 0)
					(fill yes)
				)
			)
		)
	)
	(footprint ""
		(layer "F.Cu")
		(at 252.603 -136.779 180)
		(property "Reference" "SC1311"
			(at 0 0 180)
			(layer "F.SilkS")
			(hide yes)
			(effects
				(font
					(size 1.27 1.27)
				)
			)
		)
		(property "Value" "SCD1U16V2KX-3GP"
			(at 1.1811 -2.7051 180)
			(unlocked yes)
			(layer "F.Fab")
			(hide yes)
			(effects
				(font
					(size 1.016 1.016)
					(thickness 0.1524)
				)
			)
		)
		(property "Device Type" "C402H22"
			(at 1.1811 -4.2291 180)
			(unlocked yes)
			(layer "F.Fab")
			(hide yes)
			(effects
				(font
					(size 1.016 1.016)
					(thickness 0.1524)
				)
			)
		)
		(duplicate_pad_numbers_are_jumpers no)
		(fp_rect
			(start -0.4318 0.9525)
			(end 0.4318 -0.9525)
			(stroke
				(width 0)
				(type default)
			)
			(fill no)
			(layer "F.CrtYd")
		)
		(fp_rect
			(start -0.4318 0.9525)
			(end 0.4318 -0.9525)
			(stroke
				(width 0)
				(type default)
			)
			(fill no)
			(layer "F.Fab")
		)
		(pad "1" smd custom
			(at 0 -0.4445 180)
			(size 0.1524 0.1524)
			(layers "F.Cu" "F.Mask" "F.Paste")
			(net "P3V3_STBY")
			(options
				(clearance outline)
				(anchor circle)
			)
			(primitives
				(gr_poly
					(pts
						(arc
							(start 0.3048 -0.2032)
							(mid 0.275042 -0.275042)
							(end 0.2032 -0.3048)
						)
						(arc
							(start -0.2032 -0.3048)
							(mid -0.275042 -0.275042)
							(end -0.3048 -0.2032)
						)
						(arc
							(start -0.3048 0.2032)
							(mid -0.275042 0.275042)
							(end -0.2032 0.3048)
						)
						(arc
							(start 0.2032 0.3048)
							(mid 0.275042 0.275042)
							(end 0.3048 0.2032)
						)
					)
					(width 0)
					(fill yes)
				)
			)
		)
		(pad "2" smd custom
			(at 0 0.4445 180)
			(size 0.1524 0.1524)
			(layers "F.Cu" "F.Mask" "F.Paste")
			(net "GND")
			(options
				(clearance outline)
				(anchor circle)
			)
			(primitives
				(gr_poly
					(pts
						(arc
							(start 0.3048 -0.2032)
							(mid 0.275042 -0.275042)
							(end 0.2032 -0.3048)
						)
						(arc
							(start -0.2032 -0.3048)
							(mid -0.275042 -0.275042)
							(end -0.3048 -0.2032)
						)
						(arc
							(start -0.3048 0.2032)
							(mid -0.275042 0.275042)
							(end -0.2032 0.3048)
						)
						(arc
							(start 0.2032 0.3048)
							(mid 0.275042 0.275042)
							(end 0.3048 0.2032)
						)
					)
					(width 0)
					(fill yes)
				)
			)
		)
	)
)
